(kicad_pcb
	(version 20241229)
	(generator "pcbnew")
	(generator_version "9.0")
	(general
		(thickness 1.599998)
		(legacy_teardrops no)
	)
	(paper "A4")
	(title_block
		(title "Artix - Datacenter Secure Control Module (DC-SCM)")
		(date "2024-11-06")
		(rev "1.1.3")
		(comment 9 "footprints 200-202 of 544")
	)
	(layers
		(0 "F.Cu" signal)
		(4 "In1.Cu" signal)
		(6 "In2.Cu" signal)
		(8 "In3.Cu" signal)
		(10 "In4.Cu" signal)
		(12 "In5.Cu" signal)
		(14 "In6.Cu" signal)
		(2 "B.Cu" signal)
		(9 "F.Adhes" user "F.Adhesive")
		(11 "B.Adhes" user "B.Adhesive")
		(13 "F.Paste" user)
		(15 "B.Paste" user)
		(5 "F.SilkS" user "F.Silkscreen")
		(7 "B.SilkS" user "B.Silkscreen")
		(1 "F.Mask" user)
		(3 "B.Mask" user)
		(17 "Dwgs.User" user "User.Drawings")
		(19 "Cmts.User" user "User.Comments")
		(21 "Eco1.User" user "User.Eco1")
		(23 "Eco2.User" user "User.Eco2")
		(25 "Edge.Cuts" user)
		(27 "Margin" user)
		(31 "F.CrtYd" user "F.Courtyard")
		(29 "B.CrtYd" user "B.Courtyard")
		(35 "F.Fab" user)
		(33 "B.Fab" user)
	)
	(footprint "antmicro-footprints:Conn_Plug_Molex_SlimStack_2x25_529910508"
		(layer "F.Cu")
		(at 74.071 156.39412)
		(property "Reference" "J8"
			(at 0 -4.4 0)
			(layer "F.SilkS")
			(effects
				(font
					(size 0.7 0.7)
					(thickness 0.15)
				)
				(justify left bottom)
			)
		)
		(property "Value" "Plug_Molex_SlimStack_2x25_529910508"
			(at 0 4.75 0)
			(layer "F.Fab")
			(effects
				(font
					(size 0.7 0.7)
					(thickness 0.15)
				)
				(justify left bottom)
			)
		)
		(property "Datasheet" "https://www.molex.com/en-us/products/part-detail/529910508?display=pdf"
			(at 0 0 0)
			(layer "F.Fab")
			(hide yes)
			(effects
				(font
					(size 1.27 1.27)
					(thickness 0.15)
				)
			)
		)
		(property "Description" "Mezzanine Connector, Receptacle, 0.5mm, 2Rows, 50Contacts, Surface Mount, Phosphor Bronze"
			(at 0 0 0)
			(layer "F.Fab")
			(hide yes)
			(effects
				(font
					(size 1.27 1.27)
					(thickness 0.15)
				)
			)
		)
		(property "Author" "Antmicro"
			(at 0 0 0)
			(layer "F.Fab")
			(hide yes)
			(effects
				(font
					(size 1 1)
					(thickness 0.15)
				)
			)
		)
		(property "License" "Apache-2.0"
			(at 0 0 0)
			(layer "F.Fab")
			(hide yes)
			(effects
				(font
					(size 1 1)
					(thickness 0.15)
				)
			)
		)
		(property "MPN" "529910508"
			(at 0 0 0)
			(layer "F.Fab")
			(hide yes)
			(effects
				(font
					(size 1 1)
					(thickness 0.15)
				)
			)
		)
		(property "Manufacturer" "Molex"
			(at 0 0 0)
			(layer "F.Fab")
			(hide yes)
			(effects
				(font
					(size 1 1)
					(thickness 0.15)
				)
			)
		)
		(property "Pitch " "0.5 mm"
			(at 0 0 0)
			(layer "F.Fab")
			(hide yes)
			(effects
				(font
					(size 1 1)
					(thickness 0.15)
				)
			)
		)
		(sheetname "/RoT/")
		(sheetfile "rot.kicad_sch")
		(attr smd)
		(fp_line
			(start -8.15 -2.7)
			(end -8.15 2.7)
			(stroke
				(width 0.15)
				(type solid)
			)
			(layer "F.SilkS")
		)
		(fp_line
			(start -6.7 -2.7)
			(end -8.15 -2.7)
			(stroke
				(width 0.15)
				(type solid)
			)
			(layer "F.SilkS")
		)
		(fp_line
			(start -6.7 2.7)
			(end -8.15 2.7)
			(stroke
				(width 0.15)
				(type solid)
			)
			(layer "F.SilkS")
		)
		(fp_line
			(start 6.7 -2.7)
			(end 8.15 -2.7)
			(stroke
				(width 0.15)
				(type solid)
			)
			(layer "F.SilkS")
		)
		(fp_line
			(start 6.7 2.7)
			(end 8.15 2.7)
			(stroke
				(width 0.15)
				(type solid)
			)
			(layer "F.SilkS")
		)
		(fp_line
			(start 8.15 2.7)
			(end 8.15 -2.7)
			(stroke
				(width 0.15)
				(type solid)
			)
			(layer "F.SilkS")
		)
		(fp_circle
			(center -6.45 -3.05)
			(end -6.45 -3.1)
			(stroke
				(width 0.15)
				(type solid)
			)
			(fill yes)
			(layer "F.SilkS")
		)
		(fp_line
			(start -8.657 -3.399)
			(end -8.657 3.401)
			(stroke
				(width 0.05)
				(type solid)
			)
			(layer "F.CrtYd")
		)
		(fp_line
			(start -8.657 3.401)
			(end 8.643 3.401)
			(stroke
				(width 0.05)
				(type solid)
			)
			(layer "F.CrtYd")
		)
		(fp_line
			(start 8.643 -3.399)
			(end -8.657 -3.399)
			(stroke
				(width 0.05)
				(type solid)
			)
			(layer "F.CrtYd")
		)
		(fp_line
			(start 8.643 3.401)
			(end 8.643 -3.399)
			(stroke
				(width 0.05)
				(type solid)
			)
			(layer "F.CrtYd")
		)
		(pad "1" smd rect
			(at -6.007 -2.041 180)
			(size 0.3 1.8)
			(layers "F.Cu" "F.Mask" "F.Paste")
			(net 2 "VCC3V3")
			(pintype "passive")
		)
		(pad "2" smd rect
			(at -6.007 2.058 180)
			(size 0.3 1.8)
			(layers "F.Cu" "F.Mask" "F.Paste")
			(net 1 "GND")
			(pintype "passive")
		)
		(pad "3" smd rect
			(at -5.507 -2.041 180)
			(size 0.3 1.8)
			(layers "F.Cu" "F.Mask" "F.Paste")
			(net 2 "VCC3V3")
			(pintype "passive")
		)
		(pad "4" smd rect
			(at -5.507 2.058 180)
			(size 0.3 1.8)
			(layers "F.Cu" "F.Mask" "F.Paste")
			(net 1 "GND")
			(pintype "passive")
		)
		(pad "5" smd rect
			(at -5.006 -2.05 180)
			(size 0.3 1.8)
			(layers "F.Cu" "F.Mask" "F.Paste")
			(net 566 "ROT_GPIO1")
			(pintype "passive")
		)
		(pad "6" smd rect
			(at -5.006 2.058 180)
			(size 0.3 1.8)
			(layers "F.Cu" "F.Mask" "F.Paste")
			(net 565 "ROT_GPIO2")
			(pintype "passive")
		)
		(pad "7" smd rect
			(at -4.506 -2.041 180)
			(size 0.3 1.8)
			(layers "F.Cu" "F.Mask" "F.Paste")
			(net 96 "QSPI0_CS1_N")
			(pintype "passive")
		)
		(pad "8" smd rect
			(at -4.506 2.058 180)
			(size 0.3 1.8)
			(layers "F.Cu" "F.Mask" "F.Paste")
			(net 133 "QSPIA1_D2")
			(pintype "passive")
		)
		(pad "9" smd rect
			(at -4.007 -2.041 180)
			(size 0.3 1.8)
			(layers "F.Cu" "F.Mask" "F.Paste")
			(net 138 "QSPIA2_D2")
			(pintype "passive")
		)
		(pad "10" smd rect
			(at -4.007 2.058 180)
			(size 0.3 1.8)
			(layers "F.Cu" "F.Mask" "F.Paste")
			(net 132 "QSPIA1_D1")
			(pintype "passive")
		)
		(pad "11" smd rect
			(at -3.507 -2.041 180)
			(size 0.3 1.8)
			(layers "F.Cu" "F.Mask" "F.Paste")
			(net 137 "QSPIA2_D1")
			(pintype "passive")
		)
		(pad "12" smd rect
			(at -3.507 2.058 180)
			(size 0.3 1.8)
			(layers "F.Cu" "F.Mask" "F.Paste")
			(net 135 "QSPIA1_CS_N")
			(pintype "passive")
		)
		(pad "13" smd rect
			(at -3.007 -2.041 180)
			(size 0.3 1.8)
			(layers "F.Cu" "F.Mask" "F.Paste")
			(net 140 "QSPIA2_CS_N")
			(pintype "passive")
		)
		(pad "14" smd rect
			(at -3.007 2.058 180)
			(size 0.3 1.8)
			(layers "F.Cu" "F.Mask" "F.Paste")
			(net 134 "QSPIA1_D3")
			(pintype "passive")
		)
		(pad "15" smd rect
			(at -2.507 -2.041 180)
			(size 0.3 1.8)
			(layers "F.Cu" "F.Mask" "F.Paste")
			(net 139 "QSPIA2_D3")
			(pintype "passive")
		)
		(pad "16" smd rect
			(at -2.507 2.058 180)
			(size 0.3 1.8)
			(layers "F.Cu" "F.Mask" "F.Paste")
			(net 131 "QSPIA1_D0")
			(pintype "passive")
		)
		(pad "17" smd rect
			(at -2.005 -2.041 180)
			(size 0.3 1.8)
			(layers "F.Cu" "F.Mask" "F.Paste")
			(net 130 "QSPIA_CLK")
			(pintype "passive")
		)
		(pad "18" smd rect
			(at -2.005 2.058 180)
			(size 0.3 1.8)
			(layers "F.Cu" "F.Mask" "F.Paste")
			(net 70 "QSPI0_CLK")
			(pintype "passive")
		)
		(pad "19" smd rect
			(at -1.505 -2.041 180)
			(size 0.3 1.8)
			(layers "F.Cu" "F.Mask" "F.Paste")
			(net 136 "QSPIA2_D0")
			(pintype "passive")
		)
		(pad "20" smd rect
			(at -1.505 2.058 180)
			(size 0.3 1.8)
			(layers "F.Cu" "F.Mask" "F.Paste")
			(net 71 "QSPI0_CS0_N")
			(pintype "passive")
		)
		(pad "21" smd rect
			(at -1.005 -2.041 180)
			(size 0.3 1.8)
			(layers "F.Cu" "F.Mask" "F.Paste")
			(net 122 "QSPIB1_D2")
			(pintype "passive")
		)
		(pad "22" smd rect
			(at -1.005 2.058 180)
			(size 0.3 1.8)
			(layers "F.Cu" "F.Mask" "F.Paste")
			(net 72 "QSPI0_D0")
			(pintype "passive")
		)
		(pad "23" smd rect
			(at -0.505 -2.041 180)
			(size 0.3 1.8)
			(layers "F.Cu" "F.Mask" "F.Paste")
			(net 121 "QSPIB1_D1")
			(pintype "passive")
		)
		(pad "24" smd rect
			(at -0.505 2.058 180)
			(size 0.3 1.8)
			(layers "F.Cu" "F.Mask" "F.Paste")
			(net 73 "QSPI0_D1")
			(pintype "passive")
		)
		(pad "25" smd rect
			(at -0.005 -2.041 180)
			(size 0.3 1.8)
			(layers "F.Cu" "F.Mask" "F.Paste")
			(net 124 "QSPIB1_CS_N")
			(pintype "passive")
		)
		(pad "26" smd rect
			(at -0.005 2.058 180)
			(size 0.3 1.8)
			(layers "F.Cu" "F.Mask" "F.Paste")
			(net 74 "QSPI0_D2")
			(pintype "passive")
		)
		(pad "27" smd rect
			(at 0.493 -2.041 180)
			(size 0.3 1.8)
			(layers "F.Cu" "F.Mask" "F.Paste")
			(net 123 "QSPIB1_D3")
			(pintype "passive")
		)
		(pad "28" smd rect
			(at 0.493 2.058 180)
			(size 0.3 1.8)
			(layers "F.Cu" "F.Mask" "F.Paste")
			(net 75 "QSPI0_D3")
			(pintype "passive")
		)
		(pad "29" smd rect
			(at 0.994 -2.041 180)
			(size 0.3 1.8)
			(layers "F.Cu" "F.Mask" "F.Paste")
			(net 120 "QSPIB1_D0")
			(pintype "passive")
		)
		(pad "30" smd rect
			(at 0.994 2.058 180)
			(size 0.3 1.8)
			(layers "F.Cu" "F.Mask" "F.Paste")
			(net 320 "ROT_QSPI_SCK")
			(pintype "passive")
		)
		(pad "31" smd rect
			(at 1.494 -2.041 180)
			(size 0.3 1.8)
			(layers "F.Cu" "F.Mask" "F.Paste")
			(net 127 "QSPIB2_D2")
			(pintype "passive")
		)
		(pad "32" smd rect
			(at 1.494 2.058 180)
			(size 0.3 1.8)
			(layers "F.Cu" "F.Mask" "F.Paste")
			(net 333 "ROT_QSPI_DQ3")
			(pintype "passive")
		)
		(pad "33" smd rect
			(at 1.993 -2.041 180)
			(size 0.3 1.8)
			(layers "F.Cu" "F.Mask" "F.Paste")
			(net 126 "QSPIB2_D1")
			(pintype "passive")
		)
		(pad "34" smd rect
			(at 1.993 2.058 180)
			(size 0.3 1.8)
			(layers "F.Cu" "F.Mask" "F.Paste")
			(net 332 "ROT_QSPI_DQ2")
			(pintype "passive")
		)
		(pad "35" smd rect
			(at 2.493 -2.041 180)
			(size 0.3 1.8)
			(layers "F.Cu" "F.Mask" "F.Paste")
			(net 129 "QSPIB2_CS_N")
			(pintype "passive")
		)
		(pad "36" smd rect
			(at 2.493 2.058 180)
			(size 0.3 1.8)
			(layers "F.Cu" "F.Mask" "F.Paste")
			(net 336 "ROT_QSPI_DQ1")
			(pintype "passive")
		)
		(pad "37" smd rect
			(at 2.993 -2.041 180)
			(size 0.3 1.8)
			(layers "F.Cu" "F.Mask" "F.Paste")
			(net 128 "QSPIB2_D3")
			(pintype "passive")
		)
		(pad "38" smd rect
			(at 2.993 2.058 180)
			(size 0.3 1.8)
			(layers "F.Cu" "F.Mask" "F.Paste")
			(net 335 "ROT_QSPI_DQ0")
			(pintype "passive")
		)
		(pad "39" smd rect
			(at 3.493 -2.041 180)
			(size 0.3 1.8)
			(layers "F.Cu" "F.Mask" "F.Paste")
			(net 119 "QSPIB_CLK")
			(pintype "passive")
		)
		(pad "40" smd rect
			(at 3.493 2.058 180)
			(size 0.3 1.8)
			(layers "F.Cu" "F.Mask" "F.Paste")
			(net 221 "PROGRAM")
			(pintype "passive")
		)
		(pad "41" smd rect
			(at 3.994 -2.041 180)
			(size 0.3 1.8)
			(layers "F.Cu" "F.Mask" "F.Paste")
			(net 125 "QSPIB2_D0")
			(pintype "passive")
		)
		(pad "42" smd rect
			(at 3.994 2.058 180)
			(size 0.3 1.8)
			(layers "F.Cu" "F.Mask" "F.Paste")
			(net 222 "INIT")
			(pintype "passive")
		)
		(pad "43" smd rect
			(at 4.494 -2.041 180)
			(size 0.3 1.8)
			(layers "F.Cu" "F.Mask" "F.Paste")
			(net 350 "ROT_QSPI_CS_B")
			(pintype "passive")
		)
		(pad "44" smd rect
			(at 4.494 2.058 180)
			(size 0.3 1.8)
			(layers "F.Cu" "F.Mask" "F.Paste")
			(net 301 "ROT_RDY\\ROT_GPIO0")
			(pintype "passive")
		)
		(pad "45" smd rect
			(at 4.994 -2.041 180)
			(size 0.3 1.8)
			(layers "F.Cu" "F.Mask" "F.Paste")
			(net 561 "ROT_SS")
			(pintype "passive")
		)
		(pad "46" smd rect
			(at 4.994 2.058 180)
			(size 0.3 1.8)
			(layers "F.Cu" "F.Mask" "F.Paste")
			(net 562 "ROT_TX")
			(pintype "passive")
		)
		(pad "47" smd rect
			(at 5.494 -2.041 180)
			(size 0.3 1.8)
			(layers "F.Cu" "F.Mask" "F.Paste")
			(net 559 "ROT_MISO")
			(pintype "passive")
		)
		(pad "48" smd rect
			(at 5.494 2.058 180)
			(size 0.3 1.8)
			(layers "F.Cu" "F.Mask" "F.Paste")
			(net 563 "ROT_RX")
			(pintype "passive")
		)
		(pad "49" smd rect
			(at 5.994 -2.041 180)
			(size 0.3 1.8)
			(layers "F.Cu" "F.Mask" "F.Paste")
			(net 560 "ROT_MOSI")
			(pintype "passive")
		)
		(pad "50" smd rect
			(at 5.994 2.058 180)
			(size 0.3 1.8)
			(layers "F.Cu" "F.Mask" "F.Paste")
			(net 564 "ROT_SCLK")
			(pintype "passive")
		)
	)
	(footprint "antmicro-footprints:C_0603_1608Metric"
		(layer "F.Cu")
		(at 84.59 66.74 180)
		(descr "Capacitor SMD 0603")
		(tags "capacitor 0603")
		(property "Reference" "C67"
			(at -7.31 -4.86 0)
			(layer "F.SilkS")
			(effects
				(font
					(size 0.7 0.7)
					(thickness 0.15)
				)
				(justify right bottom)
			)
		)
		(property "Value" "C_2u2_0603_25V"
			(at 0 1.6 0)
			(layer "F.Fab")
			(effects
				(font
					(size 0.7 0.7)
					(thickness 0.15)
				)
				(justify right bottom)
			)
		)
		(property "Datasheet" "https://www.murata.com/products/productdetail?partno=GRM188R61E225KA12%23"
			(at 0 0 180)
			(layer "F.Fab")
			(hide yes)
			(effects
				(font
					(size 1.27 1.27)
					(thickness 0.15)
				)
			)
		)
		(property "Description" "SMD Multilayer Ceramic Capacitor, 2.2 µF, 25 V, 0603 [1608 Metric], ± 10%, X5R, GRM Series"
			(at 0 0 180)
			(layer "F.Fab")
			(hide yes)
			(effects
				(font
					(size 1.27 1.27)
					(thickness 0.15)
				)
			)
		)
		(property "Author" "Antmicro"
			(at 169.18 133.48 0)
			(layer "F.Fab")
			(hide yes)
			(effects
				(font
					(size 1 1)
					(thickness 0.15)
				)
			)
		)
		(property "Dielectric" ""
			(at 169.18 133.48 0)
			(layer "F.Fab")
			(hide yes)
			(effects
				(font
					(size 1 1)
					(thickness 0.15)
				)
			)
		)
		(property "License" "Apache-2.0"
			(at 169.18 133.48 0)
			(layer "F.Fab")
			(hide yes)
			(effects
				(font
					(size 1 1)
					(thickness 0.15)
				)
			)
		)
		(property "MPN" "GRM188R61E225KA12D"
			(at 169.18 133.48 0)
			(layer "F.Fab")
			(hide yes)
			(effects
				(font
					(size 1 1)
					(thickness 0.15)
				)
			)
		)
		(property "Manufacturer" "Murata"
			(at 169.18 133.48 0)
			(layer "F.Fab")
			(hide yes)
			(effects
				(font
					(size 1 1)
					(thickness 0.15)
				)
			)
		)
		(property "Public" "False"
			(at 169.18 133.48 0)
			(layer "F.Fab")
			(hide yes)
			(effects
				(font
					(size 1 1)
					(thickness 0.15)
				)
			)
		)
		(property "Val" "2u2"
			(at 169.18 133.48 0)
			(layer "F.Fab")
			(hide yes)
			(effects
				(font
					(size 1 1)
					(thickness 0.15)
				)
			)
		)
		(property "Voltage" ""
			(at 169.18 133.48 0)
			(layer "F.Fab")
			(hide yes)
			(effects
				(font
					(size 1 1)
					(thickness 0.15)
				)
			)
		)
		(sheetname "/Power supply/")
		(sheetfile "power-supply.kicad_sch")
		(attr smd)
		(fp_line
			(start -0.15 0.4)
			(end 0.15 0.4)
			(stroke
				(width 0.15)
				(type solid)
			)
			(layer "F.SilkS")
		)
		(fp_line
			(start -0.15 -0.4)
			(end 0.15 -0.4)
			(stroke
				(width 0.15)
				(type solid)
			)
			(layer "F.SilkS")
		)
		(fp_rect
			(start -1.25 -0.65)
			(end 1.25 0.65)
			(stroke
				(width 0.05)
				(type solid)
			)
			(fill no)
			(layer "F.CrtYd")
		)
		(fp_rect
			(start -0.8 -0.4)
			(end 0.8 0.4)
			(stroke
				(width 0.15)
				(type solid)
			)
			(fill no)
			(layer "F.Fab")
		)
		(pad "1" smd roundrect
			(at -0.7 0 180)
			(size 0.8 1)
			(layers "F.Cu" "F.Mask" "F.Paste")
			(roundrect_rratio 0.2)
			(net 1 "GND")
			(pintype "passive")
		)
		(pad "2" smd roundrect
			(at 0.7 0 180)
			(size 0.8 1)
			(layers "F.Cu" "F.Mask" "F.Paste")
			(roundrect_rratio 0.2)
			(net 104 "/Power supply/VCC12V")
			(pintype "passive")
		)
	)
	(footprint "antmicro-footprints:C_0603_1608Metric"
		(layer "F.Cu")
		(at 84.59 65.265 180)
		(descr "Capacitor SMD 0603")
		(tags "capacitor 0603")
		(property "Reference" "C66"
			(at -7.31 -5.335 0)
			(layer "F.SilkS")
			(effects
				(font
					(size 0.7 0.7)
					(thickness 0.15)
				)
				(justify right bottom)
			)
		)
		(property "Value" "C_2u2_0603_25V"
			(at 0 1.6 0)
			(layer "F.Fab")
			(effects
				(font
					(size 0.7 0.7)
					(thickness 0.15)
				)
				(justify right bottom)
			)
		)
		(property "Datasheet" "https://www.murata.com/products/productdetail?partno=GRM188R61E225KA12%23"
			(at 0 0 180)
			(layer "F.Fab")
			(hide yes)
			(effects
				(font
					(size 1.27 1.27)
					(thickness 0.15)
				)
			)
		)
		(property "Description" "SMD Multilayer Ceramic Capacitor, 2.2 µF, 25 V, 0603 [1608 Metric], ± 10%, X5R, GRM Series"
			(at 0 0 180)
			(layer "F.Fab")
			(hide yes)
			(effects
				(font
					(size 1.27 1.27)
					(thickness 0.15)
				)
			)
		)
		(property "Author" "Antmicro"
			(at 169.18 130.53 0)
			(layer "F.Fab")
			(hide yes)
			(effects
				(font
					(size 1 1)
					(thickness 0.15)
				)
			)
		)
		(property "Dielectric" ""
			(at 169.18 130.53 0)
			(layer "F.Fab")
			(hide yes)
			(effects
				(font
					(size 1 1)
					(thickness 0.15)
				)
			)
		)
		(property "License" "Apache-2.0"
			(at 169.18 130.53 0)
			(layer "F.Fab")
			(hide yes)
			(effects
				(font
					(size 1 1)
					(thickness 0.15)
				)
			)
		)
		(property "MPN" "GRM188R61E225KA12D"
			(at 169.18 130.53 0)
			(layer "F.Fab")
			(hide yes)
			(effects
				(font
					(size 1 1)
					(thickness 0.15)
				)
			)
		)
		(property "Manufacturer" "Murata"
			(at 169.18 130.53 0)
			(layer "F.Fab")
			(hide yes)
			(effects
				(font
					(size 1 1)
					(thickness 0.15)
				)
			)
		)
		(property "Public" "False"
			(at 169.18 130.53 0)
			(layer "F.Fab")
			(hide yes)
			(effects
				(font
					(size 1 1)
					(thickness 0.15)
				)
			)
		)
		(property "Val" "2u2"
			(at 169.18 130.53 0)
			(layer "F.Fab")
			(hide yes)
			(effects
				(font
					(size 1 1)
					(thickness 0.15)
				)
			)
		)
		(property "Voltage" ""
			(at 169.18 130.53 0)
			(layer "F.Fab")
			(hide yes)
			(effects
				(font
					(size 1 1)
					(thickness 0.15)
				)
			)
		)
		(sheetname "/Power supply/")
		(sheetfile "power-supply.kicad_sch")
		(attr smd)
		(fp_line
			(start -0.15 0.4)
			(end 0.15 0.4)
			(stroke
				(width 0.15)
				(type solid)
			)
			(layer "F.SilkS")
		)
		(fp_line
			(start -0.15 -0.4)
			(end 0.15 -0.4)
			(stroke
				(width 0.15)
				(type solid)
			)
			(layer "F.SilkS")
		)
		(fp_rect
			(start -1.25 -0.65)
			(end 1.25 0.65)
			(stroke
				(width 0.05)
				(type solid)
			)
			(fill no)
			(layer "F.CrtYd")
		)
		(fp_rect
			(start -0.8 -0.4)
			(end 0.8 0.4)
			(stroke
				(width 0.15)
				(type solid)
			)
			(fill no)
			(layer "F.Fab")
		)
		(pad "1" smd roundrect
			(at -0.7 0 180)
			(size 0.8 1)
			(layers "F.Cu" "F.Mask" "F.Paste")
			(roundrect_rratio 0.2)
			(net 1 "GND")
			(pintype "passive")
		)
		(pad "2" smd roundrect
			(at 0.7 0 180)
			(size 0.8 1)
			(layers "F.Cu" "F.Mask" "F.Paste")
			(roundrect_rratio 0.2)
			(net 104 "/Power supply/VCC12V")
			(pintype "passive")
		)
	)
)
